# T6G (Grand Teton) — schematic netlist excerpt (pin names and nets, part order shuffled) for the footprints in the layout excerpt that follows; sources: Cadence DE-HDL packaged netlist, KiCad conversion of 04192023_DAF0TMB3IC0_F0TG_MB_C_brd_V02_OCP.brd

R717  Q_RES  10K 1% EMPTY  pkg 0402LF  page 238 : A = P3V3_AUX ; B = MB_FRU_ADDR1
R4208  Q_RES  200K 1% EMPTY  pkg 0402LF  page 235 : A = P3V3_AUX ; B = FM_THERMAL_ALERT_N
C6520  Q_CAP_DIFFBUS  DIFF BUS_0.22UF 6.3V 20% X6S  pkg C0201  page 275 : \1\ = P5E_CPU0_P0_TX_BUF_C_DN<9> ; \2\ = P5E_CPU0_P0_TX_BUF_DN<9>

(kicad_pcb
	(version 20260206)
	(generator "pcbnew")
	(generator_version "10.0")
	(general
		(thickness 1.6)
		(legacy_teardrops no)
	)
	(paper "A4")
	(title_block
		(title "04192023_DAF0TMB3IC0_F0TG_MB_C_brd_V02_OCP.brd")
		(comment 1 "Grand Teton / footprints 806-808 of 8354")
	)
	(layers
		(0 "F.Cu" signal "TOP")
		(4 "In1.Cu" signal "GND")
		(6 "In2.Cu" signal "IN1")
		(8 "In3.Cu" signal "GND1")
		(10 "In4.Cu" signal "IN2")
		(12 "In5.Cu" signal "GND2")
		(14 "In6.Cu" signal "IN3")
		(16 "In7.Cu" signal "GND3")
		(18 "In8.Cu" signal "VCC")
		(20 "In9.Cu" signal "VCC1")
		(22 "In10.Cu" signal "GND4")
		(24 "In11.Cu" signal "IN4")
		(26 "In12.Cu" signal "GND5")
		(28 "In13.Cu" signal "IN5")
		(30 "In14.Cu" signal "GND6")
		(32 "In15.Cu" signal "IN6")
		(34 "In16.Cu" signal "GND7")
		(2 "B.Cu" signal "BOTTOM")
		(9 "F.Adhes" user "F.Adhesive")
		(11 "B.Adhes" user "B.Adhesive")
		(13 "F.Paste" user "Package Geometry/Pastemask Top")
		(15 "B.Paste" user "Package Geometry/Pastemask Bottom")
		(5 "F.SilkS" user "Ref Des/Silkscreen Top")
		(7 "B.SilkS" user "Ref Des/Silkscreen Bottom")
		(1 "F.Mask" user "Board Geometry/Soldermask Top")
		(3 "B.Mask" user "Board Geometry/Soldermask Bottom")
		(17 "Dwgs.User" user "User.Drawings")
		(19 "Cmts.User" user "User.Comments")
		(21 "Eco1.User" user "User.Eco1")
		(23 "Eco2.User" user "User.Eco2")
		(25 "Edge.Cuts" user "Board Geometry/Outline")
		(27 "Margin" user)
		(31 "F.CrtYd" user "Package Geometry/Place Bound Top")
		(29 "B.CrtYd" user "Package Geometry/Place Bound Bottom")
		(35 "F.Fab" user "Ref Des/Assembly Top")
		(33 "B.Fab" user "Ref Des/Assembly Bottom")
	)
	(footprint ""
		(layer "F.Cu")
		(at 106.934 -13.909548 180)
		(property "Reference" "R4208"
			(at 0 0 180)
			(layer "F.SilkS")
			(hide yes)
			(effects
				(font
					(size 1.27 1.27)
				)
			)
		)
		(property "Value" ""
			(at 0 0 180)
			(layer "F.Fab")
			(effects
				(font
					(size 1.27 1.27)
				)
			)
		)
		(duplicate_pad_numbers_are_jumpers no)
		(fp_line
			(start 0.7874 0.4064)
			(end -0.7874 0.4064)
			(stroke
				(width 0.1524)
				(type default)
			)
			(layer "F.SilkS")
		)
		(fp_line
			(start 0.7874 -0.4064)
			(end 0.7874 0.4064)
			(stroke
				(width 0.1524)
				(type default)
			)
			(layer "F.SilkS")
		)
		(fp_line
			(start -0.7874 0.4064)
			(end -0.7874 -0.4064)
			(stroke
				(width 0.1524)
				(type default)
			)
			(layer "F.SilkS")
		)
		(fp_line
			(start -0.7874 -0.4064)
			(end 0.7874 -0.4064)
			(stroke
				(width 0.1524)
				(type default)
			)
			(layer "F.SilkS")
		)
		(fp_line
			(start 0.67945 0.3048)
			(end 0.120396 0.3048)
			(stroke
				(width 0.1)
				(type default)
			)
			(layer "F.Fab")
		)
		(fp_line
			(start 0.67945 -0.3048)
			(end 0.67945 0.3048)
			(stroke
				(width 0.1)
				(type default)
			)
			(layer "F.Fab")
		)
		(fp_line
			(start 0.12065 -0.2794)
			(end 0.12065 -0.3048)
			(stroke
				(width 0.1)
				(type default)
			)
			(layer "F.Fab")
		)
		(fp_line
			(start 0.12065 -0.3048)
			(end 0.67945 -0.3048)
			(stroke
				(width 0.1)
				(type default)
			)
			(layer "F.Fab")
		)
		(fp_line
			(start 0.120396 0.3048)
			(end 0.120396 0.2794)
			(stroke
				(width 0.1)
				(type default)
			)
			(layer "F.Fab")
		)
		(fp_line
			(start 0.120396 0.2794)
			(end -0.12065 0.2794)
			(stroke
				(width 0.1)
				(type default)
			)
			(layer "F.Fab")
		)
		(fp_line
			(start -0.12065 0.3048)
			(end -0.67945 0.3048)
			(stroke
				(width 0.1)
				(type default)
			)
			(layer "F.Fab")
		)
		(fp_line
			(start -0.12065 0.2794)
			(end -0.12065 0.3048)
			(stroke
				(width 0.1)
				(type default)
			)
			(layer "F.Fab")
		)
		(fp_line
			(start -0.12065 -0.2794)
			(end 0.12065 -0.2794)
			(stroke
				(width 0.1)
				(type default)
			)
			(layer "F.Fab")
		)
		(fp_line
			(start -0.12065 -0.305054)
			(end -0.12065 -0.2794)
			(stroke
				(width 0.1)
				(type default)
			)
			(layer "F.Fab")
		)
		(fp_line
			(start -0.67945 0.3048)
			(end -0.67945 -0.305054)
			(stroke
				(width 0.1)
				(type default)
			)
			(layer "F.Fab")
		)
		(fp_line
			(start -0.67945 -0.305054)
			(end -0.12065 -0.305054)
			(stroke
				(width 0.1)
				(type default)
			)
			(layer "F.Fab")
		)
		(pad "1" smd circle
			(at -0.40005 0 180)
			(size 0 0)
			(layers "F.Cu" "F.Mask" "F.Paste")
			(net "P3V3_AUX")
		)
		(pad "2" smd circle
			(at 0.40005 0 180)
			(size 0 0)
			(layers "F.Cu" "F.Mask" "F.Paste")
			(net "FM_THERMAL_ALERT_N")
		)
	)
	(footprint ""
		(layer "F.Cu")
		(at 331.337666 -416.899344 -90)
		(property "Reference" "C6520"
			(at 0 0 270)
			(layer "F.SilkS")
			(hide yes)
			(effects
				(font
					(size 1.27 1.27)
				)
			)
		)
		(property "Value" ""
			(at 0 0 270)
			(layer "F.Fab")
			(effects
				(font
					(size 1.27 1.27)
				)
			)
		)
		(duplicate_pad_numbers_are_jumpers no)
		(fp_line
			(start -0.299974 0.150114)
			(end -0.299974 -0.150114)
			(stroke
				(width 0.1)
				(type default)
			)
			(layer "F.Fab")
		)
		(fp_line
			(start 0.299974 0.150114)
			(end -0.299974 0.150114)
			(stroke
				(width 0.1)
				(type default)
			)
			(layer "F.Fab")
		)
		(fp_line
			(start -0.299974 -0.150114)
			(end 0.299974 -0.150114)
			(stroke
				(width 0.1)
				(type default)
			)
			(layer "F.Fab")
		)
		(fp_line
			(start 0.299974 -0.150114)
			(end 0.299974 0.150114)
			(stroke
				(width 0.1)
				(type default)
			)
			(layer "F.Fab")
		)
		(pad "1" smd rect
			(at -0.2667 0 270)
			(size 0.3048 0.381)
			(layers "F.Cu" "F.Mask" "F.Paste")
			(net "P5E_CPU0_P0_TX_BUF_C_DN<9>")
		)
		(pad "2" smd rect
			(at 0.2667 0 270)
			(size 0.3048 0.381)
			(layers "F.Cu" "F.Mask" "F.Paste")
			(net "P5E_CPU0_P0_TX_BUF_DN<9>")
		)
	)
	(footprint ""
		(layer "F.Cu")
		(at 305.177698 -118.179088)
		(property "Reference" "R717"
			(at 0 0 0)
			(layer "F.SilkS")
			(hide yes)
			(effects
				(font
					(size 1.27 1.27)
				)
			)
		)
		(property "Value" ""
			(at 0 0 0)
			(layer "F.Fab")
			(effects
				(font
					(size 1.27 1.27)
				)
			)
		)
		(duplicate_pad_numbers_are_jumpers no)
		(fp_line
			(start -0.7874 -0.4064)
			(end 0.7874 -0.4064)
			(stroke
				(width 0.1524)
				(type default)
			)
			(layer "F.SilkS")
		)
		(fp_line
			(start -0.7874 0.4064)
			(end -0.7874 -0.4064)
			(stroke
				(width 0.1524)
				(type default)
			)
			(layer "F.SilkS")
		)
		(fp_line
			(start 0.7874 -0.4064)
			(end 0.7874 0.4064)
			(stroke
				(width 0.1524)
				(type default)
			)
			(layer "F.SilkS")
		)
		(fp_line
			(start 0.7874 0.4064)
			(end -0.7874 0.4064)
			(stroke
				(width 0.1524)
				(type default)
			)
			(layer "F.SilkS")
		)
		(fp_line
			(start -0.67945 -0.305054)
			(end -0.12065 -0.305054)
			(stroke
				(width 0.1)
				(type default)
			)
			(layer "F.Fab")
		)
		(fp_line
			(start -0.67945 0.3048)
			(end -0.67945 -0.305054)
			(stroke
				(width 0.1)
				(type default)
			)
			(layer "F.Fab")
		)
		(fp_line
			(start -0.12065 -0.305054)
			(end -0.12065 -0.2794)
			(stroke
				(width 0.1)
				(type default)
			)
			(layer "F.Fab")
		)
		(fp_line
			(start -0.12065 -0.2794)
			(end 0.12065 -0.2794)
			(stroke
				(width 0.1)
				(type default)
			)
			(layer "F.Fab")
		)
		(fp_line
			(start -0.12065 0.2794)
			(end -0.12065 0.3048)
			(stroke
				(width 0.1)
				(type default)
			)
			(layer "F.Fab")
		)
		(fp_line
			(start -0.12065 0.3048)
			(end -0.67945 0.3048)
			(stroke
				(width 0.1)
				(type default)
			)
			(layer "F.Fab")
		)
		(fp_line
			(start 0.120396 0.2794)
			(end -0.12065 0.2794)
			(stroke
				(width 0.1)
				(type default)
			)
			(layer "F.Fab")
		)
		(fp_line
			(start 0.120396 0.3048)
			(end 0.120396 0.2794)
			(stroke
				(width 0.1)
				(type default)
			)
			(layer "F.Fab")
		)
		(fp_line
			(start 0.12065 -0.3048)
			(end 0.67945 -0.3048)
			(stroke
				(width 0.1)
				(type default)
			)
			(layer "F.Fab")
		)
		(fp_line
			(start 0.12065 -0.2794)
			(end 0.12065 -0.3048)
			(stroke
				(width 0.1)
				(type default)
			)
			(layer "F.Fab")
		)
		(fp_line
			(start 0.67945 -0.3048)
			(end 0.67945 0.3048)
			(stroke
				(width 0.1)
				(type default)
			)
			(layer "F.Fab")
		)
		(fp_line
			(start 0.67945 0.3048)
			(end 0.120396 0.3048)
			(stroke
				(width 0.1)
				(type default)
			)
			(layer "F.Fab")
		)
		(pad "1" smd circle
			(at -0.40005 0)
			(size 0 0)
			(layers "F.Cu" "F.Mask" "F.Paste")
			(net "P3V3_AUX")
		)
		(pad "2" smd circle
			(at 0.40005 0)
			(size 0 0)
			(layers "F.Cu" "F.Mask" "F.Paste")
			(net "MB_FRU_ADDR1")
		)
	)
)
